(kicad_pcb
	(version 20260206)
	(generator "pcbnew")
	(generator_version "10.0")
	(general
		(thickness 1.6)
		(legacy_teardrops no)
	)
	(paper "A4")
	(title_block
		(title "peb — Lightning_PEB_BRD.brd")
		(comment 1 "Lightning (Wiwynn / Facebook NVMe JBOF) / footprints 1816-1824 of 2563")
	)
	(layers
		(0 "F.Cu" signal "TOP")
		(4 "In1.Cu" signal "L2GND")
		(6 "In2.Cu" signal "L3")
		(8 "In3.Cu" signal "L4VCC")
		(10 "In4.Cu" signal "L5VCC")
		(12 "In5.Cu" signal "L6")
		(14 "In6.Cu" signal "L7GND")
		(2 "B.Cu" signal "BOTTOM")
		(9 "F.Adhes" user "F.Adhesive")
		(11 "B.Adhes" user "B.Adhesive")
		(13 "F.Paste" user "Package Geometry/Pastemask Top")
		(15 "B.Paste" user "Package Geometry/Pastemask Bottom")
		(5 "F.SilkS" user "Ref Des/Silkscreen Top")
		(7 "B.SilkS" user "Ref Des/Silkscreen Bottom")
		(1 "F.Mask" user "Board Geometry/Soldermask Top")
		(3 "B.Mask" user "Board Geometry/Soldermask Bottom")
		(17 "Dwgs.User" user "User.Drawings")
		(19 "Cmts.User" user "User.Comments")
		(21 "Eco1.User" user "User.Eco1")
		(23 "Eco2.User" user "User.Eco2")
		(25 "Edge.Cuts" user "Board Geometry/Outline")
		(27 "Margin" user)
		(31 "F.CrtYd" user "Package Geometry/Place Bound Top")
		(29 "B.CrtYd" user "Package Geometry/Place Bound Bottom")
		(35 "F.Fab" user "Ref Des/Assembly Top")
		(33 "B.Fab" user "Ref Des/Assembly Bottom")
	)
	(footprint ""
		(layer "B.Cu")
		(at 125.953012 -208.897474)
		(property "Reference" "R535"
			(at 0 0 0)
			(layer "B.SilkS")
			(hide yes)
			(effects
				(font
					(size 1.27 1.27)
				)
				(justify mirror)
			)
		)
		(property "Value" "10KR2F-2-GP"
			(at -0.064008 -3.993896 0)
			(unlocked yes)
			(layer "B.Fab")
			(hide yes)
			(effects
				(font
					(size 1.016 1.016)
					(thickness 0.1524)
				)
				(justify mirror)
			)
		)
		(property "Device Type" "R402H16"
			(at -0.064008 -5.517896 0)
			(unlocked yes)
			(layer "B.Fab")
			(hide yes)
			(effects
				(font
					(size 1.016 1.016)
					(thickness 0.1524)
				)
				(justify mirror)
			)
		)
		(duplicate_pad_numbers_are_jumpers no)
		(fp_line
			(start -0.508 -0.9398)
			(end 0.508 -0.9398)
			(stroke
				(width 0.1524)
				(type default)
			)
			(layer "B.SilkS")
		)
		(fp_line
			(start 0.508 -0.9398)
			(end 0.508 0.9398)
			(stroke
				(width 0.1524)
				(type default)
			)
			(layer "B.SilkS")
		)
		(fp_rect
			(start 0.508 0.9398)
			(end -0.508 -0.9398)
			(stroke
				(width 0)
				(type default)
			)
			(fill no)
			(layer "B.CrtYd")
		)
		(fp_rect
			(start 0.508 0.9398)
			(end -0.508 -0.9398)
			(stroke
				(width 0)
				(type default)
			)
			(fill no)
			(layer "B.Fab")
		)
		(pad "1" smd custom
			(at 0 -0.4445 180)
			(size 0.1397 0.1397)
			(layers "B.Cu" "B.Mask" "B.Paste")
			(net "P3V3_STBY")
			(options
				(clearance outline)
				(anchor circle)
			)
			(primitives
				(gr_poly
					(pts
						(arc
							(start -0.1778 0.2794)
							(mid -0.249642 0.249642)
							(end -0.2794 0.1778)
						)
						(arc
							(start -0.2794 -0.1778)
							(mid -0.249642 -0.249642)
							(end -0.1778 -0.2794)
						)
						(arc
							(start 0.1778 -0.2794)
							(mid 0.249642 -0.249642)
							(end 0.2794 -0.1778)
						)
						(arc
							(start 0.2794 0.1778)
							(mid 0.249642 0.249642)
							(end 0.1778 0.2794)
						)
					)
					(width 0)
					(fill yes)
				)
			)
		)
		(pad "2" smd custom
			(at 0 0.4445 180)
			(size 0.1397 0.1397)
			(layers "B.Cu" "B.Mask" "B.Paste")
			(net "IOEXP2_AD0")
			(options
				(clearance outline)
				(anchor circle)
			)
			(primitives
				(gr_poly
					(pts
						(arc
							(start -0.1778 0.2794)
							(mid -0.249642 0.249642)
							(end -0.2794 0.1778)
						)
						(arc
							(start -0.2794 -0.1778)
							(mid -0.249642 -0.249642)
							(end -0.1778 -0.2794)
						)
						(arc
							(start 0.1778 -0.2794)
							(mid 0.249642 -0.249642)
							(end 0.2794 -0.1778)
						)
						(arc
							(start 0.2794 0.1778)
							(mid 0.249642 0.249642)
							(end 0.1778 0.2794)
						)
					)
					(width 0)
					(fill yes)
				)
			)
		)
	)
	(footprint ""
		(layer "B.Cu")
		(at 243.59997 -40.999918 90)
		(property "Reference" "TP264"
			(at 0 0 90)
			(layer "B.SilkS")
			(hide yes)
			(effects
				(font
					(size 1.27 1.27)
				)
				(justify mirror)
			)
		)
		(property "Value" "TPAD28-2-GP"
			(at 0.0127 -1.6637 90)
			(unlocked yes)
			(layer "B.Fab")
			(hide yes)
			(effects
				(font
					(size 1.016 1.016)
					(thickness 0.1524)
				)
				(justify mirror)
			)
		)
		(property "Device Type" "TPAD28"
			(at 0.0127 -3.1877 90)
			(unlocked yes)
			(layer "B.Fab")
			(hide yes)
			(effects
				(font
					(size 1.016 1.016)
					(thickness 0.1524)
				)
				(justify mirror)
			)
		)
		(duplicate_pad_numbers_are_jumpers no)
		(fp_poly
			(pts
				(arc
					(start 0 0.3556)
					(mid 0 -0.3556)
					(end 0 0.3556)
				)
			)
			(stroke
				(width 0)
				(type default)
			)
			(fill no)
			(layer "B.CrtYd")
		)
		(fp_poly
			(pts
				(arc
					(start 0 0.6096)
					(mid 0 -0.6096)
					(end 0 0.6096)
				)
			)
			(stroke
				(width 0)
				(type default)
			)
			(fill no)
			(layer "B.Fab")
		)
		(pad "1" smd circle
			(at 0 0 270)
			(size 0.7112 0.7112)
			(layers "B.Cu" "B.Mask" "B.Paste")
			(net "LBI_DATA_7")
		)
	)
	(footprint ""
		(layer "B.Cu")
		(at 20.1168 -121.5644 -90)
		(property "Reference" "R225"
			(at 0 0 90)
			(layer "B.SilkS")
			(hide yes)
			(effects
				(font
					(size 1.27 1.27)
				)
				(justify mirror)
			)
		)
		(property "Value" "4K7R2F-GP"
			(at -0.064008 -3.993896 270)
			(unlocked yes)
			(layer "B.Fab")
			(hide yes)
			(effects
				(font
					(size 1.016 1.016)
					(thickness 0.1524)
				)
				(justify mirror)
			)
		)
		(property "Device Type" "R402H16"
			(at -0.064008 -5.517896 270)
			(unlocked yes)
			(layer "B.Fab")
			(hide yes)
			(effects
				(font
					(size 1.016 1.016)
					(thickness 0.1524)
				)
				(justify mirror)
			)
		)
		(duplicate_pad_numbers_are_jumpers no)
		(fp_line
			(start -0.508 -0.9398)
			(end 0.508 -0.9398)
			(stroke
				(width 0.1524)
				(type default)
			)
			(layer "B.SilkS")
		)
		(fp_line
			(start 0.508 -0.9398)
			(end 0.508 0.9398)
			(stroke
				(width 0.1524)
				(type default)
			)
			(layer "B.SilkS")
		)
		(fp_rect
			(start 0.508 0.9398)
			(end -0.508 -0.9398)
			(stroke
				(width 0)
				(type default)
			)
			(fill no)
			(layer "B.CrtYd")
		)
		(fp_rect
			(start 0.508 0.9398)
			(end -0.508 -0.9398)
			(stroke
				(width 0)
				(type default)
			)
			(fill no)
			(layer "B.Fab")
		)
		(pad "1" smd custom
			(at 0 -0.4445 90)
			(size 0.1397 0.1397)
			(layers "B.Cu" "B.Mask" "B.Paste")
			(net "DPB_HW_REVISION")
			(options
				(clearance outline)
				(anchor circle)
			)
			(primitives
				(gr_poly
					(pts
						(arc
							(start -0.1778 0.2794)
							(mid -0.249642 0.249642)
							(end -0.2794 0.1778)
						)
						(arc
							(start -0.2794 -0.1778)
							(mid -0.249642 -0.249642)
							(end -0.1778 -0.2794)
						)
						(arc
							(start 0.1778 -0.2794)
							(mid 0.249642 -0.249642)
							(end 0.2794 -0.1778)
						)
						(arc
							(start 0.2794 0.1778)
							(mid 0.249642 0.249642)
							(end 0.1778 0.2794)
						)
					)
					(width 0)
					(fill yes)
				)
			)
		)
		(pad "2" smd custom
			(at 0 0.4445 90)
			(size 0.1397 0.1397)
			(layers "B.Cu" "B.Mask" "B.Paste")
			(net "P3V3_STBY")
			(options
				(clearance outline)
				(anchor circle)
			)
			(primitives
				(gr_poly
					(pts
						(arc
							(start -0.1778 0.2794)
							(mid -0.249642 0.249642)
							(end -0.2794 0.1778)
						)
						(arc
							(start -0.2794 -0.1778)
							(mid -0.249642 -0.249642)
							(end -0.1778 -0.2794)
						)
						(arc
							(start 0.1778 -0.2794)
							(mid 0.249642 -0.249642)
							(end 0.2794 -0.1778)
						)
						(arc
							(start 0.2794 0.1778)
							(mid 0.249642 0.249642)
							(end 0.1778 0.2794)
						)
					)
					(width 0)
					(fill yes)
				)
			)
		)
	)
	(footprint ""
		(layer "B.Cu")
		(at 135.935212 -199.753474)
		(property "Reference" "C3207"
			(at 0 0 0)
			(layer "B.SilkS")
			(hide yes)
			(effects
				(font
					(size 1.27 1.27)
				)
				(justify mirror)
			)
		)
		(property "Value" "SCD1U25V2KX-2-GP"
			(at -1.1811 -2.7051 0)
			(unlocked yes)
			(layer "B.Fab")
			(hide yes)
			(effects
				(font
					(size 1.016 1.016)
					(thickness 0.1524)
				)
				(justify mirror)
			)
		)
		(property "Device Type" "C402H22"
			(at -1.1811 -4.2291 0)
			(unlocked yes)
			(layer "B.Fab")
			(hide yes)
			(effects
				(font
					(size 1.016 1.016)
					(thickness 0.1524)
				)
				(justify mirror)
			)
		)
		(duplicate_pad_numbers_are_jumpers no)
		(fp_rect
			(start 0.4318 0.9525)
			(end -0.4318 -0.9525)
			(stroke
				(width 0)
				(type default)
			)
			(fill no)
			(layer "B.CrtYd")
		)
		(fp_rect
			(start 0.4318 0.9525)
			(end -0.4318 -0.9525)
			(stroke
				(width 0)
				(type default)
			)
			(fill no)
			(layer "B.Fab")
		)
		(pad "1" smd custom
			(at 0 -0.4445 180)
			(size 0.1524 0.1524)
			(layers "B.Cu" "B.Mask" "B.Paste")
			(net "P3V3_STBY")
			(options
				(clearance outline)
				(anchor circle)
			)
			(primitives
				(gr_poly
					(pts
						(arc
							(start 0.3048 0.2032)
							(mid 0.275042 0.275042)
							(end 0.2032 0.3048)
						)
						(arc
							(start -0.2032 0.3048)
							(mid -0.275042 0.275042)
							(end -0.3048 0.2032)
						)
						(arc
							(start -0.3048 -0.2032)
							(mid -0.275042 -0.275042)
							(end -0.2032 -0.3048)
						)
						(arc
							(start 0.2032 -0.3048)
							(mid 0.275042 -0.275042)
							(end 0.3048 -0.2032)
						)
					)
					(width 0)
					(fill yes)
				)
			)
		)
		(pad "2" smd custom
			(at 0 0.4445 180)
			(size 0.1524 0.1524)
			(layers "B.Cu" "B.Mask" "B.Paste")
			(net "GND")
			(options
				(clearance outline)
				(anchor circle)
			)
			(primitives
				(gr_poly
					(pts
						(arc
							(start 0.3048 0.2032)
							(mid 0.275042 0.275042)
							(end 0.2032 0.3048)
						)
						(arc
							(start -0.2032 0.3048)
							(mid -0.275042 0.275042)
							(end -0.3048 0.2032)
						)
						(arc
							(start -0.3048 -0.2032)
							(mid -0.275042 -0.275042)
							(end -0.2032 -0.3048)
						)
						(arc
							(start 0.2032 -0.3048)
							(mid 0.275042 -0.275042)
							(end 0.3048 -0.2032)
						)
					)
					(width 0)
					(fill yes)
				)
			)
		)
	)
	(footprint ""
		(layer "B.Cu")
		(at 60.1472 -25.4508)
		(property "Reference" "R571"
			(at 0 0 0)
			(layer "B.SilkS")
			(hide yes)
			(effects
				(font
					(size 1.27 1.27)
				)
				(justify mirror)
			)
		)
		(property "Value" "10KR2F-2-GP"
			(at -0.064008 -3.993896 0)
			(unlocked yes)
			(layer "B.Fab")
			(hide yes)
			(effects
				(font
					(size 1.016 1.016)
					(thickness 0.1524)
				)
				(justify mirror)
			)
		)
		(property "Device Type" "R402H16"
			(at -0.064008 -5.517896 0)
			(unlocked yes)
			(layer "B.Fab")
			(hide yes)
			(effects
				(font
					(size 1.016 1.016)
					(thickness 0.1524)
				)
				(justify mirror)
			)
		)
		(duplicate_pad_numbers_are_jumpers no)
		(fp_line
			(start -0.508 -0.9398)
			(end 0.508 -0.9398)
			(stroke
				(width 0.1524)
				(type default)
			)
			(layer "B.SilkS")
		)
		(fp_line
			(start 0.508 -0.9398)
			(end 0.508 0.9398)
			(stroke
				(width 0.1524)
				(type default)
			)
			(layer "B.SilkS")
		)
		(fp_rect
			(start 0.508 0.9398)
			(end -0.508 -0.9398)
			(stroke
				(width 0)
				(type default)
			)
			(fill no)
			(layer "B.CrtYd")
		)
		(fp_rect
			(start 0.508 0.9398)
			(end -0.508 -0.9398)
			(stroke
				(width 0)
				(type default)
			)
			(fill no)
			(layer "B.Fab")
		)
		(pad "1" smd custom
			(at 0 -0.4445 180)
			(size 0.1397 0.1397)
			(layers "B.Cu" "B.Mask" "B.Paste")
			(net "P3V3_STBY")
			(options
				(clearance outline)
				(anchor circle)
			)
			(primitives
				(gr_poly
					(pts
						(arc
							(start -0.1778 0.2794)
							(mid -0.249642 0.249642)
							(end -0.2794 0.1778)
						)
						(arc
							(start -0.2794 -0.1778)
							(mid -0.249642 -0.249642)
							(end -0.1778 -0.2794)
						)
						(arc
							(start 0.1778 -0.2794)
							(mid 0.249642 -0.249642)
							(end 0.2794 -0.1778)
						)
						(arc
							(start 0.2794 0.1778)
							(mid 0.249642 0.249642)
							(end 0.1778 0.2794)
						)
					)
					(width 0)
					(fill yes)
				)
			)
		)
		(pad "2" smd custom
			(at 0 0.4445 180)
			(size 0.1397 0.1397)
			(layers "B.Cu" "B.Mask" "B.Paste")
			(net "BMC_INT_N")
			(options
				(clearance outline)
				(anchor circle)
			)
			(primitives
				(gr_poly
					(pts
						(arc
							(start -0.1778 0.2794)
							(mid -0.249642 0.249642)
							(end -0.2794 0.1778)
						)
						(arc
							(start -0.2794 -0.1778)
							(mid -0.249642 -0.249642)
							(end -0.1778 -0.2794)
						)
						(arc
							(start 0.1778 -0.2794)
							(mid 0.249642 -0.249642)
							(end 0.2794 -0.1778)
						)
						(arc
							(start 0.2794 0.1778)
							(mid 0.249642 0.249642)
							(end 0.1778 0.2794)
						)
					)
					(width 0)
					(fill yes)
				)
			)
		)
	)
	(footprint ""
		(layer "B.Cu")
		(at 314.071 -68.58 180)
		(property "Reference" "PC182"
			(at 0 0 0)
			(layer "B.SilkS")
			(hide yes)
			(effects
				(font
					(size 1.27 1.27)
				)
				(justify mirror)
			)
		)
		(property "Value" "SC22U6D3V5MX-5-GP"
			(at 0.0762 -6.1214 180)
			(unlocked yes)
			(layer "B.Fab")
			(hide yes)
			(effects
				(font
					(size 1.016 1.016)
					(thickness 0.1524)
				)
				(justify mirror)
			)
		)
		(property "Device Type" "C805H56"
			(at 0.0762 -8.1534 180)
			(unlocked yes)
			(layer "B.Fab")
			(hide yes)
			(effects
				(font
					(size 1.016 1.016)
					(thickness 0.1524)
				)
				(justify mirror)
			)
		)
		(duplicate_pad_numbers_are_jumpers no)
		(fp_line
			(start -0.635 0)
			(end 0.635 0)
			(stroke
				(width 0.508)
				(type default)
			)
			(layer "B.SilkS")
		)
		(fp_rect
			(start 0.9652 1.778)
			(end -0.9652 -1.778)
			(stroke
				(width 0)
				(type default)
			)
			(fill no)
			(layer "B.CrtYd")
		)
		(fp_poly
			(pts
				(xy 0.9652 -1.778) (xy -0.9652 -1.778) (xy -0.9652 1.778) (xy 0.9652 1.778)
			)
			(stroke
				(width 0)
				(type default)
			)
			(fill no)
			(layer "B.Fab")
		)
		(pad "1" smd rect
			(at 0 -0.9652)
			(size 1.397 1.143)
			(layers "B.Cu" "B.Mask" "B.Paste")
			(net "P0V9_E")
		)
		(pad "2" smd rect
			(at 0 0.9652)
			(size 1.397 1.143)
			(layers "B.Cu" "B.Mask" "B.Paste")
			(net "GND")
		)
	)
	(footprint ""
		(layer "B.Cu")
		(at 42.418 -138.557)
		(property "Reference" "TP231"
			(at 0 0 0)
			(layer "B.SilkS")
			(hide yes)
			(effects
				(font
					(size 1.27 1.27)
				)
				(justify mirror)
			)
		)
		(property "Value" "TPAD28-2-GP"
			(at 0.0127 -1.6637 0)
			(unlocked yes)
			(layer "B.Fab")
			(hide yes)
			(effects
				(font
					(size 1.016 1.016)
					(thickness 0.1524)
				)
				(justify mirror)
			)
		)
		(property "Device Type" "TPAD28"
			(at 0.0127 -3.1877 0)
			(unlocked yes)
			(layer "B.Fab")
			(hide yes)
			(effects
				(font
					(size 1.016 1.016)
					(thickness 0.1524)
				)
				(justify mirror)
			)
		)
		(duplicate_pad_numbers_are_jumpers no)
		(fp_poly
			(pts
				(arc
					(start 0.3556 0)
					(mid -0.3556 0)
					(end 0.3556 0)
				)
			)
			(stroke
				(width 0)
				(type default)
			)
			(fill no)
			(layer "B.CrtYd")
		)
		(fp_poly
			(pts
				(arc
					(start 0.6096 0)
					(mid -0.6096 0)
					(end 0.6096 0)
				)
			)
			(stroke
				(width 0)
				(type default)
			)
			(fill no)
			(layer "B.Fab")
		)
		(pad "1" smd circle
			(at 0 0 180)
			(size 0.7112 0.7112)
			(layers "B.Cu" "B.Mask" "B.Paste")
			(net "TP_GPIOP2")
		)
	)
	(footprint ""
		(layer "B.Cu")
		(at 228.6254 -45.991272 90)
		(property "Reference" "C490"
			(at 0 0 90)
			(layer "B.SilkS")
			(hide yes)
			(effects
				(font
					(size 1.27 1.27)
				)
				(justify mirror)
			)
		)
		(property "Value" "SCD1U16V1KX-1-GP"
			(at 2.8321 -1.7399 90)
			(unlocked yes)
			(layer "B.Fab")
			(hide yes)
			(effects
				(font
					(size 1.016 1.016)
					(thickness 0.1524)
				)
				(justify mirror)
			)
		)
		(property "Device Type" "C0201H13"
			(at 2.8321 -3.2639 90)
			(unlocked yes)
			(layer "B.Fab")
			(hide yes)
			(effects
				(font
					(size 1.016 1.016)
					(thickness 0.1524)
				)
				(justify mirror)
			)
		)
		(duplicate_pad_numbers_are_jumpers no)
		(fp_rect
			(start 0.2794 0.6477)
			(end -0.2794 -0.6477)
			(stroke
				(width 0)
				(type default)
			)
			(fill no)
			(layer "B.CrtYd")
		)
		(fp_rect
			(start 0.2794 0.6477)
			(end -0.2794 -0.6477)
			(stroke
				(width 0)
				(type default)
			)
			(fill no)
			(layer "B.Fab")
		)
		(pad "1" smd custom
			(at 0 -0.2794 270)
			(size 0.0762 0.0762)
			(layers "B.Cu" "B.Mask" "B.Paste")
			(net "DUT_AVD_PCIE")
			(options
				(clearance outline)
				(anchor circle)
			)
			(primitives
				(gr_poly
					(pts
						(arc
							(start 0.1524 0.127)
							(mid 0.137521 0.162921)
							(end 0.1016 0.1778)
						)
						(arc
							(start -0.1016 0.1778)
							(mid -0.137521 0.162921)
							(end -0.1524 0.127)
						)
						(arc
							(start -0.1524 -0.127)
							(mid -0.137521 -0.162921)
							(end -0.1016 -0.1778)
						)
						(arc
							(start 0.1016 -0.1778)
							(mid 0.137521 -0.162921)
							(end 0.1524 -0.127)
						)
					)
					(width 0)
					(fill yes)
				)
			)
		)
		(pad "2" smd custom
			(at 0 0.2794 270)
			(size 0.0762 0.0762)
			(layers "B.Cu" "B.Mask" "B.Paste")
			(net "GND")
			(options
				(clearance outline)
				(anchor circle)
			)
			(primitives
				(gr_poly
					(pts
						(arc
							(start 0.1524 0.127)
							(mid 0.137521 0.162921)
							(end 0.1016 0.1778)
						)
						(arc
							(start -0.1016 0.1778)
							(mid -0.137521 0.162921)
							(end -0.1524 0.127)
						)
						(arc
							(start -0.1524 -0.127)
							(mid -0.137521 -0.162921)
							(end -0.1016 -0.1778)
						)
						(arc
							(start 0.1016 -0.1778)
							(mid 0.137521 -0.162921)
							(end 0.1524 -0.127)
						)
					)
					(width 0)
					(fill yes)
				)
			)
		)
	)
	(footprint ""
		(layer "B.Cu")
		(at 228.6254 -51.998372 90)
		(property "Reference" "C561"
			(at 0 0 90)
			(layer "B.SilkS")
			(hide yes)
			(effects
				(font
					(size 1.27 1.27)
				)
				(justify mirror)
			)
		)
		(property "Value" "SCD1U16V1KX-1-GP"
			(at 2.8321 -1.7399 90)
			(unlocked yes)
			(layer "B.Fab")
			(hide yes)
			(effects
				(font
					(size 1.016 1.016)
					(thickness 0.1524)
				)
				(justify mirror)
			)
		)
		(property "Device Type" "C0201H13"
			(at 2.8321 -3.2639 90)
			(unlocked yes)
			(layer "B.Fab")
			(hide yes)
			(effects
				(font
					(size 1.016 1.016)
					(thickness 0.1524)
				)
				(justify mirror)
			)
		)
		(duplicate_pad_numbers_are_jumpers no)
		(fp_rect
			(start 0.2794 0.6477)
			(end -0.2794 -0.6477)
			(stroke
				(width 0)
				(type default)
			)
			(fill no)
			(layer "B.CrtYd")
		)
		(fp_rect
			(start 0.2794 0.6477)
			(end -0.2794 -0.6477)
			(stroke
				(width 0)
				(type default)
			)
			(fill no)
			(layer "B.Fab")
		)
		(pad "1" smd custom
			(at 0 -0.2794 270)
			(size 0.0762 0.0762)
			(layers "B.Cu" "B.Mask" "B.Paste")
			(net "DUT_AVD_PCIE")
			(options
				(clearance outline)
				(anchor circle)
			)
			(primitives
				(gr_poly
					(pts
						(arc
							(start 0.1524 0.127)
							(mid 0.137521 0.162921)
							(end 0.1016 0.1778)
						)
						(arc
							(start -0.1016 0.1778)
							(mid -0.137521 0.162921)
							(end -0.1524 0.127)
						)
						(arc
							(start -0.1524 -0.127)
							(mid -0.137521 -0.162921)
							(end -0.1016 -0.1778)
						)
						(arc
							(start 0.1016 -0.1778)
							(mid 0.137521 -0.162921)
							(end 0.1524 -0.127)
						)
					)
					(width 0)
					(fill yes)
				)
			)
		)
		(pad "2" smd custom
			(at 0 0.2794 270)
			(size 0.0762 0.0762)
			(layers "B.Cu" "B.Mask" "B.Paste")
			(net "GND")
			(options
				(clearance outline)
				(anchor circle)
			)
			(primitives
				(gr_poly
					(pts
						(arc
							(start 0.1524 0.127)
							(mid 0.137521 0.162921)
							(end 0.1016 0.1778)
						)
						(arc
							(start -0.1016 0.1778)
							(mid -0.137521 0.162921)
							(end -0.1524 0.127)
						)
						(arc
							(start -0.1524 -0.127)
							(mid -0.137521 -0.162921)
							(end -0.1016 -0.1778)
						)
						(arc
							(start 0.1016 -0.1778)
							(mid 0.137521 -0.162921)
							(end 0.1524 -0.127)
						)
					)
					(width 0)
					(fill yes)
				)
			)
		)
	)
)
